# TIMECARD (Time Appliance Project (Time Card)) — schematic netlist excerpt (pin names and nets, part order shuffled) for the footprints in the layout excerpt that follows; sources: Cadence DE-HDL packaged netlist, KiCad conversion of R4006-B0001-02_R01.brd

C108  CAPACITOR  0.1UF 10V 10%  pkg SMC_0402R_H022  page 14 : \1\ = XP2R5V_FPGA ; \2\ = SG
C203  CAPACITOR  0.1UF 10V 10%  pkg SMC_0402R_H022  page 14 : \1\ = XP3R3V_FPGA ; \2\ = SG

(kicad_pcb
	(version 20260206)
	(generator "pcbnew")
	(generator_version "10.0")
	(general
		(thickness 1.6)
		(legacy_teardrops no)
	)
	(paper "A4")
	(title_block
		(title "timecard-production-celestica-r4006 — R4006-B0001-02_R01.brd")
		(comment 1 "Time Appliance Project (Time Card) / footprints 993-994 of 1113")
	)
	(layers
		(0 "F.Cu" signal "TOP")
		(4 "In1.Cu" signal "L02_GND1")
		(6 "In2.Cu" signal "L03_SIG1")
		(8 "In3.Cu" signal "L04_GND2")
		(10 "In4.Cu" signal "L05_VCC1")
		(12 "In5.Cu" signal "L06_VCC2")
		(14 "In6.Cu" signal "L07_GND3")
		(16 "In7.Cu" signal "L08_SIG2")
		(18 "In8.Cu" signal "L09_GND4")
		(2 "B.Cu" signal "BOTTOM")
		(9 "F.Adhes" user "F.Adhesive")
		(11 "B.Adhes" user "B.Adhesive")
		(13 "F.Paste" user "Package Geometry/Pastemask Top")
		(15 "B.Paste" user "Package Geometry/Pastemask Bottom")
		(5 "F.SilkS" user "Ref Des/Silkscreen Top")
		(7 "B.SilkS" user "Ref Des/Silkscreen Bottom")
		(1 "F.Mask" user "Board Geometry/Soldermask Top")
		(3 "B.Mask" user "Board Geometry/Soldermask Bottom")
		(17 "Dwgs.User" user "User.Drawings")
		(19 "Cmts.User" user "User.Comments")
		(21 "Eco1.User" user "User.Eco1")
		(23 "Eco2.User" user "User.Eco2")
		(25 "Edge.Cuts" user "Board Geometry/Outline")
		(27 "Margin" user)
		(31 "F.CrtYd" user "Package Geometry/Place Bound Top")
		(29 "B.CrtYd" user "Package Geometry/Place Bound Bottom")
		(35 "F.Fab" user "Ref Des/Assembly Top")
		(33 "B.Fab" user "Ref Des/Assembly Bottom")
	)
	(footprint ""
		(layer "B.Cu")
		(at 100.347018 -46.823122 180)
		(property "Reference" "C203"
			(at 2.303018 -0.118872 0)
			(unlocked yes)
			(layer "B.SilkS")
			(effects
				(font
					(size 0.635 0.4064)
					(thickness 0.1524)
				)
				(justify mirror)
			)
		)
		(property "Value" "VAL*"
			(at 0 3.718306 180)
			(unlocked yes)
			(layer "B.Fab")
			(hide yes)
			(effects
				(font
					(size 0.7874 0.5842)
					(thickness 0.127)
				)
				(justify mirror)
			)
		)
		(property "Device Type" "CAPACITOR-G105-0B104-CK,0.1UF,A"
			(at 0 1.432306 180)
			(unlocked yes)
			(layer "B.Fab")
			(hide yes)
			(effects
				(font
					(size 0.7874 0.5842)
					(thickness 0.127)
				)
				(justify mirror)
			)
		)
		(property "User Part Number" "PARTNUM*"
			(at 0 2.575306 180)
			(unlocked yes)
			(layer "Cmts.User")
			(hide yes)
			(effects
				(font
					(size 0.7874 0.5842)
					(thickness 0.127)
				)
				(justify mirror)
			)
		)
		(property "Tolerance" "TOL*"
			(at 0 4.861306 180)
			(unlocked yes)
			(layer "Cmts.User")
			(hide yes)
			(effects
				(font
					(size 0.7874 0.5842)
					(thickness 0.127)
				)
				(justify mirror)
			)
		)
		(duplicate_pad_numbers_are_jumpers no)
		(fp_line
			(start 0.970026 0.4699)
			(end 0.970026 -0.4699)
			(stroke
				(width 0.1)
				(type default)
			)
			(layer "B.SilkS")
		)
		(fp_line
			(start 0.970026 -0.4699)
			(end -0.970026 -0.4699)
			(stroke
				(width 0.1)
				(type default)
			)
			(layer "B.SilkS")
		)
		(fp_line
			(start -0.970026 0.4699)
			(end 0.970026 0.4699)
			(stroke
				(width 0.1)
				(type default)
			)
			(layer "B.SilkS")
		)
		(fp_line
			(start -0.970026 -0.4699)
			(end -0.970026 0.4699)
			(stroke
				(width 0.1)
				(type default)
			)
			(layer "B.SilkS")
		)
		(fp_poly
			(pts
				(xy 0.970026 0.4699) (xy -0.970026 0.4699) (xy -0.970026 -0.4699) (xy 0.970026 -0.4699)
			)
			(stroke
				(width 0)
				(type default)
			)
			(fill no)
			(layer "B.CrtYd")
		)
		(fp_line
			(start 0.508 0.3048)
			(end 0.508 -0.3048)
			(stroke
				(width 0.1)
				(type default)
			)
			(layer "B.Fab")
		)
		(fp_line
			(start 0.508 -0.3048)
			(end -0.508 -0.3048)
			(stroke
				(width 0.1)
				(type default)
			)
			(layer "B.Fab")
		)
		(fp_line
			(start -0.508 0.3048)
			(end 0.508 0.3048)
			(stroke
				(width 0.1)
				(type default)
			)
			(layer "B.Fab")
		)
		(fp_line
			(start -0.508 -0.3048)
			(end -0.508 0.3048)
			(stroke
				(width 0.1)
				(type default)
			)
			(layer "B.Fab")
		)
		(pad "1" smd circle
			(at 0.500126 0)
			(size 0.635 0.635)
			(layers "B.Cu" "B.Mask" "B.Paste")
			(net "XP3R3V_FPGA")
		)
		(pad "2" smd circle
			(at -0.500126 0)
			(size 0.635 0.635)
			(layers "B.Cu" "B.Mask" "B.Paste")
			(net "SG")
		)
	)
	(footprint ""
		(layer "B.Cu")
		(at 111.847122 -34.32302 -90)
		(property "Reference" "C108"
			(at 2.06502 -0.008128 270)
			(unlocked yes)
			(layer "B.SilkS")
			(effects
				(font
					(size 0.635 0.4064)
					(thickness 0.1524)
				)
				(justify mirror)
			)
		)
		(property "Value" "VAL*"
			(at 0 3.718306 270)
			(unlocked yes)
			(layer "B.Fab")
			(hide yes)
			(effects
				(font
					(size 0.7874 0.5842)
					(thickness 0.127)
				)
				(justify mirror)
			)
		)
		(property "Tolerance" "TOL*"
			(at 0 4.861306 270)
			(unlocked yes)
			(layer "Cmts.User")
			(hide yes)
			(effects
				(font
					(size 0.7874 0.5842)
					(thickness 0.127)
				)
				(justify mirror)
			)
		)
		(property "User Part Number" "PARTNUM*"
			(at 0 2.575306 270)
			(unlocked yes)
			(layer "Cmts.User")
			(hide yes)
			(effects
				(font
					(size 0.7874 0.5842)
					(thickness 0.127)
				)
				(justify mirror)
			)
		)
		(property "Device Type" "CAPACITOR-G105-0B104-CK,0.1UF,A"
			(at 0 1.432306 270)
			(unlocked yes)
			(layer "B.Fab")
			(hide yes)
			(effects
				(font
					(size 0.7874 0.5842)
					(thickness 0.127)
				)
				(justify mirror)
			)
		)
		(duplicate_pad_numbers_are_jumpers no)
		(fp_line
			(start -0.970026 0.4699)
			(end 0.970026 0.4699)
			(stroke
				(width 0.1)
				(type default)
			)
			(layer "B.SilkS")
		)
		(fp_line
			(start 0.970026 0.4699)
			(end 0.970026 -0.4699)
			(stroke
				(width 0.1)
				(type default)
			)
			(layer "B.SilkS")
		)
		(fp_line
			(start -0.970026 -0.4699)
			(end -0.970026 0.4699)
			(stroke
				(width 0.1)
				(type default)
			)
			(layer "B.SilkS")
		)
		(fp_line
			(start 0.970026 -0.4699)
			(end -0.970026 -0.4699)
			(stroke
				(width 0.1)
				(type default)
			)
			(layer "B.SilkS")
		)
		(fp_poly
			(pts
				(xy 0.970026 0.4699) (xy -0.970026 0.4699) (xy -0.970026 -0.4699) (xy 0.970026 -0.4699)
			)
			(stroke
				(width 0)
				(type default)
			)
			(fill no)
			(layer "B.CrtYd")
		)
		(fp_line
			(start -0.508 0.3048)
			(end 0.508 0.3048)
			(stroke
				(width 0.1)
				(type default)
			)
			(layer "B.Fab")
		)
		(fp_line
			(start 0.508 0.3048)
			(end 0.508 -0.3048)
			(stroke
				(width 0.1)
				(type default)
			)
			(layer "B.Fab")
		)
		(fp_line
			(start -0.508 -0.3048)
			(end -0.508 0.3048)
			(stroke
				(width 0.1)
				(type default)
			)
			(layer "B.Fab")
		)
		(fp_line
			(start 0.508 -0.3048)
			(end -0.508 -0.3048)
			(stroke
				(width 0.1)
				(type default)
			)
			(layer "B.Fab")
		)
		(pad "1" smd circle
			(at 0.500126 0 90)
			(size 0.635 0.635)
			(layers "B.Cu" "B.Mask" "B.Paste")
			(net "XP2R5V_FPGA")
		)
		(pad "2" smd circle
			(at -0.500126 0 90)
			(size 0.635 0.635)
			(layers "B.Cu" "B.Mask" "B.Paste")
			(net "SG")
		)
	)
)
